# S9S_MB_2U (Grand Teton) — schematic netlist excerpt (pin names and nets, part order shuffled) for the footprints in the layout excerpt that follows; sources: Cadence DE-HDL packaged netlist, KiCad conversion of 03242023_DA0F0TMBIJ0_F0T_Motherboard_J_brd_V01_OCP.brd

J30  SCONN288_ADR50017P087CC  SCONN288_ADR50017-P087CC IO  pkg DDR288S_1-1VXB  page 111
  VIN_BULK0  = P12V_S3_AUX_CPU1_NVDIMM
  RFU0  = TP_CHG_CPU1_DIMM2_FRU_0
  VIN_MGMT  = P3V3_AUX
  HSCL  = I3C_SPD_DDREFGH_CPU1_LVC1_SCL_5
  HSDA  = I3C_SPD_DDREFGH_CPU1_LVC1_SDA
  VSS0  = GND
  DQ0_A  = M_G_CPU1_SA_DQ<0>
  VSS1  = GND
  DQ1_A  = M_G_CPU1_SA_DQ<1>
  VSS2  = GND
  DQS0_A_T  = M_G_CPU1_SA_DQS_DP<0>
  DQS0_A_C  = M_G_CPU1_SA_DQS_DN<0>
  VSS3  = GND
  DQ4_A  = M_G_CPU1_SA_DQ<4>
  VSS4  = GND
  DQ5_A  = M_G_CPU1_SA_DQ<5>
  VSS5  = GND
  DQ8_A  = M_G_CPU1_SA_DQ<8>
  VSS6  = GND
  DQ9_A  = M_G_CPU1_SA_DQ<9>
  VSS7  = GND
  DQS1_A_T  = M_G_CPU1_SA_DQS_DP<1>
  DQS1_A_C  = M_G_CPU1_SA_DQS_DN<1>
  VSS8  = GND
  DQ12_A  = M_G_CPU1_SA_DQ<12>
  VSS9  = GND
  DQ13_A  = M_G_CPU1_SA_DQ<13>
  VSS10  = GND
  DQ16_A  = M_G_CPU1_SA_DQ<16>
  VSS11  = GND
  DQ17_A  = M_G_CPU1_SA_DQ<17>
  VSS12  = GND
  DQS2_A_T  = M_G_CPU1_SA_DQS_DP<2>
  DQS2_A_C  = M_G_CPU1_SA_DQS_DN<2>
  VSS13  = GND
  DQ20_A  = M_G_CPU1_SA_DQ<20>
  VSS14  = GND
  DQ21_A  = M_G_CPU1_SA_DQ<21>
  VSS15  = GND
  DQ24_A  = M_G_CPU1_SA_DQ<24>
  VSS16  = GND
  DQ25_A  = M_G_CPU1_SA_DQ<25>
  VSS17  = GND
  DQS3_A_T  = M_G_CPU1_SA_DQS_DP<3>
  DQS3_A_C  = M_G_CPU1_SA_DQS_DN<3>
  VSS18  = GND
  DQ28_A  = M_G_CPU1_SA_DQ<28>
  VSS19  = GND
  DQ29_A  = M_G_CPU1_SA_DQ<29>
  VSS20  = GND
  CB0_A  = M_G_CPU1_SA_CB<0>
  VSS21  = GND
  CB1_A  = M_G_CPU1_SA_CB<1>
  VSS22  = GND
  DQS4_A_T  = M_G_CPU1_SA_DQS_DP<4>
  DQS4_A_C  = M_G_CPU1_SA_DQS_DN<4>
  VSS23  = GND
  CB4_A  = M_G_CPU1_SA_CB<4>
  VSS24  = GND
  CB5_A  = M_G_CPU1_SA_CB<5>
  VSS25  = GND
  ALERT_N  = M_G_CPU1_ALERT_N
  VSS26  = GND
  CS0_A_N  = M_G_CPU1_SA_CS_N<2>
  VSS27  = GND
  CA0_A  = M_G_CPU1_SA_CA<0>
  VSS28  = GND
  CA2_A  = M_G_CPU1_SA_CA<2>
  VSS29  = GND
  CA4_A  = M_G_CPU1_SA_CA<4>
  VSS30  = GND
  CA6_A  = M_G_CPU1_SA_CA<6>
  VSS31  = GND
  PAR_A  = M_G_CPU1_SA_PAR
  VSS32  = GND
  CA0_B  = M_G_CPU1_SB_CA<0>
  VSS33  = GND
  CA2_B  = M_G_CPU1_SB_CA<2>
  VSS34  = GND
  CA4_B  = M_G_CPU1_SB_CA<4>
  VSS35  = GND
  CA6_B  = M_G_CPU1_SB_CA<6>
  VSS36  = GND
  CS0_B_N  = M_G_CPU1_SB_CS_N<2>
  VSS37  = GND
  \lbd||rsp_a_n\  = M_G_CPU1_SA_RSP<1>
  \lbs||rsp_b_n\  = M_G_CPU1_SB_RSP<1>
  VSS38  = GND
  CB4_B  = M_G_CPU1_SB_CB<4>
  VSS39  = GND
  CB5_B  = M_G_CPU1_SB_CB<5>
  VSS40  = GND
  \dqs9_b_t||tdqs9_b_t||dbi4_b_n\  = M_G_CPU1_SB_DQS_DP<9>
  \dqs9_b_c||tdqs9_b_c\  = M_G_CPU1_SB_DQS_DN<9>
  VSS41  = GND
  CB0_B  = M_G_CPU1_SB_CB<0>
  VSS42  = GND
  CB1_B  = M_G_CPU1_SB_CB<1>
  VSS43  = GND
  DQ0_B  = M_G_CPU1_SB_DQ<0>
  VSS44  = GND
  DQ1_B  = M_G_CPU1_SB_DQ<1>
  VSS45  = GND
  DQS0_B_T  = M_G_CPU1_SB_DQS_DP<0>
  DQS0_B_C  = M_G_CPU1_SB_DQS_DN<0>
  VSS46  = GND
  DQ4_B  = M_G_CPU1_SB_DQ<4>
  VSS47  = GND
  DQ5_B  = M_G_CPU1_SB_DQ<5>
  VSS48  = GND
  DQ8_B  = M_G_CPU1_SB_DQ<8>
  VSS49  = GND
  DQ9_B  = M_G_CPU1_SB_DQ<9>
  VSS50  = GND
  DQS1_B_T  = M_G_CPU1_SB_DQS_DP<1>
  DQS1_B_C  = M_G_CPU1_SB_DQS_DN<1>
  VSS51  = GND
  DQ12_B  = M_G_CPU1_SB_DQ<12>
  VSS52  = GND
  DQ13_B  = M_G_CPU1_SB_DQ<13>
  VSS53  = GND
  DQ16_B  = M_G_CPU1_SB_DQ<16>
  VSS54  = GND
  DQ17_B  = M_G_CPU1_SB_DQ<17>
  VSS55  = GND
  DQS2_B_T  = M_G_CPU1_SB_DQS_DP<2>
  DQS2_B_C  = M_G_CPU1_SB_DQS_DN<2>
  VSS56  = GND
  DQ20_B  = M_G_CPU1_SB_DQ<20>
  VSS57  = GND
  DQ21_B  = M_G_CPU1_SB_DQ<21>
  VSS58  = GND
  DQ24_B  = M_G_CPU1_SB_DQ<24>
  VSS59  = GND
  DQ25_B  = M_G_CPU1_SB_DQ<25>
  VSS60  = GND
  DQS3_B_T  = M_G_CPU1_SB_DQS_DP<3>
  DQS3_B_C  = M_G_CPU1_SB_DQS_DN<3>
  VSS61  = GND
  DQ28_B  = M_G_CPU1_SB_DQ<28>
  VSS62  = GND
  DQ29_B  = M_G_CPU1_SB_DQ<29>
  VSS63  = GND
  RFU1  = TP_CHG_CPU1_DIMM2_FRU_1
  VIN_BULK1  = P12V_S3_AUX_CPU1_NVDIMM
  VIN_BULK2  = P12V_S3_AUX_CPU1_NVDIMM
  \pwr_good||fail_n\  = PWRGD_CHG_CPU1_DIMM2
  HSA  = PD_CHG_CPU1_DIMM2_SAA
  RFU2  = TP_CHG_CPU1_DIMM2_FRU_2
  RFU3  = TP_CHG_CPU1_DIMM2_FRU_3
  VSS64  = GND
  DQ2_A  = M_G_CPU1_SA_DQ<2>
  VSS65  = GND
  DQ3_A  = M_G_CPU1_SA_DQ<3>
  VSS66  = GND
  \dqs5_a_c||tdqs5_a_c||dqs5_a_t||tdqs5_a_t\  = M_G_CPU1_SA_DQS_DN<5>
  \dqs5_a_t||tdqs5_a_t\  = M_G_CPU1_SA_DQS_DP<5>
  VSS67  = GND
  DQ6_A  = M_G_CPU1_SA_DQ<6>
  VSS68  = GND
  DQ7_A  = M_G_CPU1_SA_DQ<7>
  VSS69  = GND
  DQ10_A  = M_G_CPU1_SA_DQ<10>
  VSS70  = GND
  DQ11_A  = M_G_CPU1_SA_DQ<11>
  VSS71  = GND
  \dqs6_a_c||tdqs6_a_c||dqs6_a_t||tdqs6_a_t\  = M_G_CPU1_SA_DQS_DN<6>
  \dqs6_a_t||tdqs6_a_t\  = M_G_CPU1_SA_DQS_DP<6>
  VSS72  = GND
  DQ14_A  = M_G_CPU1_SA_DQ<14>
  VSS73  = GND
  DQ15_A  = M_G_CPU1_SA_DQ<15>
  VSS74  = GND
  DQ18_A  = M_G_CPU1_SA_DQ<18>
  VSS75  = GND
  DQ19_A  = M_G_CPU1_SA_DQ<19>
  VSS76  = GND
  \dqs7_a_c||tdqs7_a_c\  = M_G_CPU1_SA_DQS_DN<7>
  \dqs7_a_t||tdqs7_a_t\  = M_G_CPU1_SA_DQS_DP<7>
  VSS77  = GND
  DQ22_A  = M_G_CPU1_SA_DQ<22>
  VSS78  = GND
  DQ23_A  = M_G_CPU1_SA_DQ<23>
  VSS79  = GND
  DQ26_A  = M_G_CPU1_SA_DQ<26>
  VSS80  = GND
  DQ27_A  = M_G_CPU1_SA_DQ<27>
  VSS81  = GND
  \dqs8_a_c||tdqs8_a_c\  = M_G_CPU1_SA_DQS_DN<8>
  \dqs8_a_t||tdqs8_a_t\  = M_G_CPU1_SA_DQS_DP<8>
  VSS82  = GND
  DQ30_A  = M_G_CPU1_SA_DQ<30>
  VSS83  = GND
  DQ31_A  = M_G_CPU1_SA_DQ<31>
  VSS84  = GND
  CB2_A  = M_G_CPU1_SA_CB<2>
  VSS85  = GND
  CB3_A  = M_G_CPU1_SA_CB<3>
  VSS86  = GND
  \dqs9_a_c||tdqs9_a_c\  = M_G_CPU1_SA_DQS_DN<9>
  \dqs9_a_t||tdqs9_a_t\  = M_G_CPU1_SA_DQS_DP<9>
  VSS87  = GND
  CB6_A  = M_G_CPU1_SA_CB<6>
  VSS88  = GND
  CB7_A  = M_G_CPU1_SA_CB<7>
  VSS89  = GND
  RESET_N  = RST_M_GH_CPU1_FPGA_N
  VSS90  = GND
  CS1_A_N  = M_G_CPU1_SA_CS_N<3>
  VSS91  = GND
  CA1_A  = M_G_CPU1_SA_CA<1>
  VSS92  = GND
  CA3_A  = M_G_CPU1_SA_CA<3>
  VSS93  = GND
  CA5_A  = M_G_CPU1_SA_CA<5>
  VSS94  = GND
  CK_T  = M_G_CPU1_CLK_DP<1>
  CK_C  = M_G_CPU1_CLK_DN<1>
  VSS95  = GND
  RFU4  = TP_CHG_CPU1_DIMM2_FRU_4
  CA1_B  = M_G_CPU1_SB_CA<1>
  VSS96  = GND
  CA3_B  = M_G_CPU1_SB_CA<3>
  VSS97  = GND
  CA5_B  = M_G_CPU1_SB_CA<5>
  VSS98  = GND
  PAR_B  = M_G_CPU1_SB_PAR
  VSS99  = GND
  CS1_B_N  = M_G_CPU1_SB_CS_N<3>
  VSS100  = GND
  RFU5  = TP_CHG_CPU1_DIMM2_FRU_5
  RFU6  = TP_CHG_CPU1_DIMM2_FRU_6
  VSS101  = GND
  CB6_B  = M_G_CPU1_SB_CB<6>
  VSS102  = GND
  CB7_B  = M_G_CPU1_SB_CB<7>
  VSS103  = GND
  DQS4_B_C  = M_G_CPU1_SB_DQS_DN<4>
  DQS4_B_T  = M_G_CPU1_SB_DQS_DP<4>
  VSS104  = GND
  CB2_B  = M_G_CPU1_SB_CB<2>
  VSS105  = GND
  CB3_B  = M_G_CPU1_SB_CB<3>
  VSS106  = GND
  DQ2_B  = M_G_CPU1_SB_DQ<2>
  VSS107  = GND
  DQ3_B  = M_G_CPU1_SB_DQ<3>
  VSS108  = GND
  \dqs5_b_c||tdqs5_b_c\  = M_G_CPU1_SB_DQS_DN<5>
  \dqs5_b_t||tdqs5_b_t\  = M_G_CPU1_SB_DQS_DP<5>
  VSS109  = GND
  DQ6_B  = M_G_CPU1_SB_DQ<6>
  VSS110  = GND
  DQ7_B  = M_G_CPU1_SB_DQ<7>
  VSS111  = GND
  DQ10_B  = M_G_CPU1_SB_DQ<10>
  VSS112  = GND
  DQ11_B  = M_G_CPU1_SB_DQ<11>
  VSS113  = GND
  \dqs6_b_c||tdqs6_b_c\  = M_G_CPU1_SB_DQS_DN<6>
  \dqs6_b_t||tdqs6_b_t\  = M_G_CPU1_SB_DQS_DP<6>
  VSS114  = GND
  DQ14_B  = M_G_CPU1_SB_DQ<14>
  VSS115  = GND
  DQ15_B  = M_G_CPU1_SB_DQ<15>
  VSS116  = GND
  DQ18_B  = M_G_CPU1_SB_DQ<18>
  VSS117  = GND
  DQ19_B  = M_G_CPU1_SB_DQ<19>
  VSS118  = GND
  \dqs7_b_c||tdqs7_b_c\  = M_G_CPU1_SB_DQS_DN<7>
  \dqs7_b_t||tdqs7_b_t\  = M_G_CPU1_SB_DQS_DP<7>
  VSS119  = GND
  DQ22_B  = M_G_CPU1_SB_DQ<22>
  VSS120  = GND
  DQ23_B  = M_G_CPU1_SB_DQ<23>
  VSS121  = GND
  DQ26_B  = M_G_CPU1_SB_DQ<26>
  VSS122  = GND
  DQ27_B  = M_G_CPU1_SB_DQ<27>
  VSS123  = GND
  \dqs8_b_c||tdqs8_b_c\  = M_G_CPU1_SB_DQS_DN<8>
  \dqs8_b_t||tdqs8_b_t\  = M_G_CPU1_SB_DQS_DP<8>
  VSS124  = GND
  DQ30_B  = M_G_CPU1_SB_DQ<30>
  VSS125  = GND
  DQ31_B  = M_G_CPU1_SB_DQ<31>
  VSS126  = GND
  G1  = GND
  G2  = GND
  G3  = GND

(kicad_pcb
	(version 20260206)
	(generator "pcbnew")
	(generator_version "10.0")
	(general
		(thickness 1.6)
		(legacy_teardrops no)
	)
	(paper "A4")
	(title_block
		(title "03242023_DA0F0TMBIJ0_F0T_Motherboard_J_brd_V01_OCP.brd")
		(comment 1 "Grand Teton / footprint 1354 of 6105 (J30), pads 229-274 of 291")
	)
	(layers
		(0 "F.Cu" signal "TOP")
		(4 "In1.Cu" signal "GND")
		(6 "In2.Cu" signal "IN1")
		(8 "In3.Cu" signal "GND1")
		(10 "In4.Cu" signal "IN2")
		(12 "In5.Cu" signal "GND2")
		(14 "In6.Cu" signal "IN3")
		(16 "In7.Cu" signal "GND3")
		(18 "In8.Cu" signal "VCC")
		(20 "In9.Cu" signal "VCC1")
		(22 "In10.Cu" signal "GND4")
		(24 "In11.Cu" signal "IN4")
		(26 "In12.Cu" signal "GND5")
		(28 "In13.Cu" signal "IN5")
		(30 "In14.Cu" signal "GND6")
		(32 "In15.Cu" signal "IN6")
		(34 "In16.Cu" signal "GND7")
		(2 "B.Cu" signal "BOTTOM")
		(9 "F.Adhes" user "F.Adhesive")
		(11 "B.Adhes" user "B.Adhesive")
		(13 "F.Paste" user "Package Geometry/Pastemask Top")
		(15 "B.Paste" user "Package Geometry/Pastemask Bottom")
		(5 "F.SilkS" user "Ref Des/Silkscreen Top")
		(7 "B.SilkS" user "Ref Des/Silkscreen Bottom")
		(1 "F.Mask" user "Board Geometry/Soldermask Top")
		(3 "B.Mask" user "Board Geometry/Soldermask Bottom")
		(17 "Dwgs.User" user "User.Drawings")
		(19 "Cmts.User" user "User.Comments")
		(21 "Eco1.User" user "User.Eco1")
		(23 "Eco2.User" user "User.Eco2")
		(25 "Edge.Cuts" user "Board Geometry/Outline")
		(27 "Margin" user)
		(31 "F.CrtYd" user "Package Geometry/Place Bound Top")
		(29 "B.CrtYd" user "Package Geometry/Place Bound Bottom")
		(35 "F.Fab" user "Ref Des/Assembly Top")
		(33 "B.Fab" user "Ref Des/Assembly Bottom")
	)
	(footprint ""
		(layer "F.Cu")
		(at 191.03848 -258.091686)
		(property "Reference" "J30"
			(at -2.98196 -81.740248 0)
			(unlocked yes)
			(layer "F.SilkS")
			(effects
				(font
					(size 0.7874 0.5842)
					(thickness 0.1524)
				)
				(justify left)
			)
		)
		(property "Value" ""
			(at 0 0 0)
			(layer "F.Fab")
			(effects
				(font
					(size 1.27 1.27)
				)
			)
		)
		(duplicate_pad_numbers_are_jumpers no)
		(pad "229" smd rect
			(at 2.050034 13.17498 270)
			(size 0.519938 1.4986)
			(layers "F.Cu" "F.Mask" "F.Paste")
			(net "M_G_CPU1_SB_CS_N<3>")
		)
		(pad "230" smd rect
			(at 2.050034 14.025118 270)
			(size 0.519938 1.4986)
			(layers "F.Cu" "F.Mask" "F.Paste")
			(net "GND")
		)
		(pad "231" smd rect
			(at 2.050034 14.875002 270)
			(size 0.519938 1.4986)
			(layers "F.Cu" "F.Mask" "F.Paste")
			(net "TP_CHG_CPU1_DIMM2_FRU_5")
		)
		(pad "232" smd rect
			(at 2.050034 15.724886 270)
			(size 0.519938 1.4986)
			(layers "F.Cu" "F.Mask" "F.Paste")
			(net "TP_CHG_CPU1_DIMM2_FRU_6")
		)
		(pad "233" smd rect
			(at 2.050034 16.575024 270)
			(size 0.519938 1.4986)
			(layers "F.Cu" "F.Mask" "F.Paste")
			(net "GND")
		)
		(pad "234" smd rect
			(at 2.050034 17.424908 270)
			(size 0.519938 1.4986)
			(layers "F.Cu" "F.Mask" "F.Paste")
			(net "M_G_CPU1_SB_CB<6>")
		)
		(pad "235" smd rect
			(at 2.050034 18.275046 270)
			(size 0.519938 1.4986)
			(layers "F.Cu" "F.Mask" "F.Paste")
			(net "GND")
		)
		(pad "236" smd rect
			(at 2.050034 19.12493 270)
			(size 0.519938 1.4986)
			(layers "F.Cu" "F.Mask" "F.Paste")
			(net "M_G_CPU1_SB_CB<7>")
		)
		(pad "237" smd rect
			(at 2.050034 19.975068 270)
			(size 0.519938 1.4986)
			(layers "F.Cu" "F.Mask" "F.Paste")
			(net "GND")
		)
		(pad "238" smd rect
			(at 2.050034 20.824952 270)
			(size 0.519938 1.4986)
			(layers "F.Cu" "F.Mask" "F.Paste")
			(net "M_G_CPU1_SB_DQS_DN<4>")
		)
		(pad "239" smd rect
			(at 2.050034 21.67509 270)
			(size 0.519938 1.4986)
			(layers "F.Cu" "F.Mask" "F.Paste")
			(net "M_G_CPU1_SB_DQS_DP<4>")
		)
		(pad "240" smd rect
			(at 2.050034 22.524974 270)
			(size 0.519938 1.4986)
			(layers "F.Cu" "F.Mask" "F.Paste")
			(net "GND")
		)
		(pad "241" smd rect
			(at 2.050034 23.375112 270)
			(size 0.519938 1.4986)
			(layers "F.Cu" "F.Mask" "F.Paste")
			(net "M_G_CPU1_SB_CB<2>")
		)
		(pad "242" smd rect
			(at 2.050034 24.224996 270)
			(size 0.519938 1.4986)
			(layers "F.Cu" "F.Mask" "F.Paste")
			(net "GND")
		)
		(pad "243" smd rect
			(at 2.050034 25.07488 270)
			(size 0.519938 1.4986)
			(layers "F.Cu" "F.Mask" "F.Paste")
			(net "M_G_CPU1_SB_CB<3>")
		)
		(pad "244" smd rect
			(at 2.050034 25.925018 270)
			(size 0.519938 1.4986)
			(layers "F.Cu" "F.Mask" "F.Paste")
			(net "GND")
		)
		(pad "245" smd rect
			(at 2.050034 26.774902 270)
			(size 0.519938 1.4986)
			(layers "F.Cu" "F.Mask" "F.Paste")
			(net "M_G_CPU1_SB_DQ<2>")
		)
		(pad "246" smd rect
			(at 2.050034 27.62504 270)
			(size 0.519938 1.4986)
			(layers "F.Cu" "F.Mask" "F.Paste")
			(net "GND")
		)
		(pad "247" smd rect
			(at 2.050034 28.474924 270)
			(size 0.519938 1.4986)
			(layers "F.Cu" "F.Mask" "F.Paste")
			(net "M_G_CPU1_SB_DQ<3>")
		)
		(pad "248" smd rect
			(at 2.050034 29.325062 270)
			(size 0.519938 1.4986)
			(layers "F.Cu" "F.Mask" "F.Paste")
			(net "GND")
		)
		(pad "249" smd rect
			(at 2.050034 30.174946 270)
			(size 0.519938 1.4986)
			(layers "F.Cu" "F.Mask" "F.Paste")
			(net "M_G_CPU1_SB_DQS_DN<5>")
		)
		(pad "250" smd rect
			(at 2.050034 31.025084 270)
			(size 0.519938 1.4986)
			(layers "F.Cu" "F.Mask" "F.Paste")
			(net "M_G_CPU1_SB_DQS_DP<5>")
		)
		(pad "251" smd rect
			(at 2.050034 31.874968 270)
			(size 0.519938 1.4986)
			(layers "F.Cu" "F.Mask" "F.Paste")
			(net "GND")
		)
		(pad "252" smd rect
			(at 2.050034 32.725106 270)
			(size 0.519938 1.4986)
			(layers "F.Cu" "F.Mask" "F.Paste")
			(net "M_G_CPU1_SB_DQ<6>")
		)
		(pad "253" smd rect
			(at 2.050034 33.57499 270)
			(size 0.519938 1.4986)
			(layers "F.Cu" "F.Mask" "F.Paste")
			(net "GND")
		)
		(pad "254" smd rect
			(at 2.050034 34.425128 270)
			(size 0.519938 1.4986)
			(layers "F.Cu" "F.Mask" "F.Paste")
			(net "M_G_CPU1_SB_DQ<7>")
		)
		(pad "255" smd rect
			(at 2.050034 35.275012 270)
			(size 0.519938 1.4986)
			(layers "F.Cu" "F.Mask" "F.Paste")
			(net "GND")
		)
		(pad "256" smd rect
			(at 2.050034 36.124896 270)
			(size 0.519938 1.4986)
			(layers "F.Cu" "F.Mask" "F.Paste")
			(net "M_G_CPU1_SB_DQ<10>")
		)
		(pad "257" smd rect
			(at 2.050034 36.975034 270)
			(size 0.519938 1.4986)
			(layers "F.Cu" "F.Mask" "F.Paste")
			(net "GND")
		)
		(pad "258" smd rect
			(at 2.050034 37.824918 270)
			(size 0.519938 1.4986)
			(layers "F.Cu" "F.Mask" "F.Paste")
			(net "M_G_CPU1_SB_DQ<11>")
		)
		(pad "259" smd rect
			(at 2.050034 38.675056 270)
			(size 0.519938 1.4986)
			(layers "F.Cu" "F.Mask" "F.Paste")
			(net "GND")
		)
		(pad "260" smd rect
			(at 2.050034 39.52494 270)
			(size 0.519938 1.4986)
			(layers "F.Cu" "F.Mask" "F.Paste")
			(net "M_G_CPU1_SB_DQS_DN<6>")
		)
		(pad "261" smd rect
			(at 2.050034 40.375078 270)
			(size 0.519938 1.4986)
			(layers "F.Cu" "F.Mask" "F.Paste")
			(net "M_G_CPU1_SB_DQS_DP<6>")
		)
		(pad "262" smd rect
			(at 2.050034 41.224962 270)
			(size 0.519938 1.4986)
			(layers "F.Cu" "F.Mask" "F.Paste")
			(net "GND")
		)
		(pad "263" smd rect
			(at 2.050034 42.0751 270)
			(size 0.519938 1.4986)
			(layers "F.Cu" "F.Mask" "F.Paste")
			(net "M_G_CPU1_SB_DQ<14>")
		)
		(pad "264" smd rect
			(at 2.050034 42.924984 270)
			(size 0.519938 1.4986)
			(layers "F.Cu" "F.Mask" "F.Paste")
			(net "GND")
		)
		(pad "265" smd rect
			(at 2.050034 43.775122 270)
			(size 0.519938 1.4986)
			(layers "F.Cu" "F.Mask" "F.Paste")
			(net "M_G_CPU1_SB_DQ<15>")
		)
		(pad "266" smd rect
			(at 2.050034 44.625006 270)
			(size 0.519938 1.4986)
			(layers "F.Cu" "F.Mask" "F.Paste")
			(net "GND")
		)
		(pad "267" smd rect
			(at 2.050034 45.47489 270)
			(size 0.519938 1.4986)
			(layers "F.Cu" "F.Mask" "F.Paste")
			(net "M_G_CPU1_SB_DQ<18>")
		)
		(pad "268" smd rect
			(at 2.050034 46.325028 270)
			(size 0.519938 1.4986)
			(layers "F.Cu" "F.Mask" "F.Paste")
			(net "GND")
		)
		(pad "269" smd rect
			(at 2.050034 47.174912 270)
			(size 0.519938 1.4986)
			(layers "F.Cu" "F.Mask" "F.Paste")
			(net "M_G_CPU1_SB_DQ<19>")
		)
		(pad "270" smd rect
			(at 2.050034 48.02505 270)
			(size 0.519938 1.4986)
			(layers "F.Cu" "F.Mask" "F.Paste")
			(net "GND")
		)
		(pad "271" smd rect
			(at 2.050034 48.874934 270)
			(size 0.519938 1.4986)
			(layers "F.Cu" "F.Mask" "F.Paste")
			(net "M_G_CPU1_SB_DQS_DN<7>")
		)
		(pad "272" smd rect
			(at 2.050034 49.725072 270)
			(size 0.519938 1.4986)
			(layers "F.Cu" "F.Mask" "F.Paste")
			(net "M_G_CPU1_SB_DQS_DP<7>")
		)
		(pad "273" smd rect
			(at 2.050034 50.574956 270)
			(size 0.519938 1.4986)
			(layers "F.Cu" "F.Mask" "F.Paste")
			(net "GND")
		)
		(pad "274" smd rect
			(at 2.050034 51.425094 270)
			(size 0.519938 1.4986)
			(layers "F.Cu" "F.Mask" "F.Paste")
			(net "M_G_CPU1_SB_DQ<22>")
		)
	)
)
